# BASEBOARD_FAB2 (Tioga Pass) — schematic netlist excerpt (pin names and nets, part order shuffled) for the footprints in the layout excerpt that follows; sources: Cadence DE-HDL packaged netlist, KiCad conversion of Wiwynn_Tioga_Pass_MB.brd

R1D42  RES  11K 1% CHIP  pkg 0402  page 199 : A = A_HSC_UV ; B = AGND_HSC
C3G2  CAP_A  47UF 4V 20% X5R  pkg 0603V  page 225 : A = PVDDQ_GHJ ; B = GND
C4F2  CAP_A  47UF 4V 20% X5R  pkg 0603V  page 193 : A = P1V8_MCP_CPU1 ; B = GND

(kicad_pcb
	(version 20260206)
	(generator "pcbnew")
	(generator_version "10.0")
	(general
		(thickness 1.6)
		(legacy_teardrops no)
	)
	(paper "A4")
	(title_block
		(title "Wiwynn_Tioga_Pass_MB.brd")
		(comment 1 "Tioga Pass / footprints 1582-1584 of 4770")
	)
	(layers
		(0 "F.Cu" signal "TOP")
		(4 "In1.Cu" signal "L2GND")
		(6 "In2.Cu" signal "L3")
		(8 "In3.Cu" signal "L4GND")
		(10 "In4.Cu" signal "L5")
		(12 "In5.Cu" signal "L6GND")
		(14 "In6.Cu" signal "L7VCC")
		(16 "In7.Cu" signal "L8VCC")
		(18 "In8.Cu" signal "L9GND")
		(20 "In9.Cu" signal "L10")
		(22 "In10.Cu" signal "L11GND")
		(24 "In11.Cu" signal "L12")
		(26 "In12.Cu" signal "L13GND")
		(2 "B.Cu" signal "BOTTOM")
		(9 "F.Adhes" user "F.Adhesive")
		(11 "B.Adhes" user "B.Adhesive")
		(13 "F.Paste" user "Package Geometry/Pastemask Top")
		(15 "B.Paste" user "Package Geometry/Pastemask Bottom")
		(5 "F.SilkS" user "Ref Des/Silkscreen Top")
		(7 "B.SilkS" user "Ref Des/Silkscreen Bottom")
		(1 "F.Mask" user "Board Geometry/Soldermask Top")
		(3 "B.Mask" user "Board Geometry/Soldermask Bottom")
		(17 "Dwgs.User" user "User.Drawings")
		(19 "Cmts.User" user "User.Comments")
		(21 "Eco1.User" user "User.Eco1")
		(23 "Eco2.User" user "User.Eco2")
		(25 "Edge.Cuts" user "Board Geometry/Outline")
		(27 "Margin" user)
		(31 "F.CrtYd" user "Package Geometry/Place Bound Top")
		(29 "B.CrtYd" user "Package Geometry/Place Bound Bottom")
		(35 "F.Fab" user "Ref Des/Assembly Top")
		(33 "B.Fab" user "Ref Des/Assembly Bottom")
	)
	(footprint ""
		(layer "F.Cu")
		(at 164.480494 -34.671)
		(property "Reference" "C4F2"
			(at 0 0 0)
			(layer "F.SilkS")
			(hide yes)
			(effects
				(font
					(size 1.27 1.27)
				)
			)
		)
		(property "Value" ""
			(at 0 0 0)
			(layer "F.Fab")
			(effects
				(font
					(size 1.27 1.27)
				)
			)
		)
		(duplicate_pad_numbers_are_jumpers no)
		(fp_rect
			(start -0.500126 1.598422)
			(end 0.500126 -0.201422)
			(stroke
				(width 0)
				(type default)
			)
			(fill no)
			(layer "F.CrtYd")
		)
		(fp_line
			(start -0.500126 -0.201422)
			(end 0.500126 -0.201422)
			(stroke
				(width 0.1)
				(type default)
			)
			(layer "F.Fab")
		)
		(fp_line
			(start -0.500126 1.598422)
			(end -0.500126 -0.201422)
			(stroke
				(width 0.1)
				(type default)
			)
			(layer "F.Fab")
		)
		(fp_line
			(start 0.500126 -0.201422)
			(end 0.500126 1.598422)
			(stroke
				(width 0.1)
				(type default)
			)
			(layer "F.Fab")
		)
		(fp_line
			(start 0.500126 1.598422)
			(end -0.500126 1.598422)
			(stroke
				(width 0.1)
				(type default)
			)
			(layer "F.Fab")
		)
		(pad "1" smd rect
			(at 0 0 270)
			(size 0.889 0.9906)
			(layers "F.Cu" "F.Mask" "F.Paste")
			(net "P1V8_MCP_CPU1")
		)
		(pad "2" smd rect
			(at 0 1.397 270)
			(size 0.889 0.9906)
			(layers "F.Cu" "F.Mask" "F.Paste")
			(net "GND")
		)
		(zone
			(layer "F.Cu")
			(hatch none 0.5)
			(connect_pads
				(clearance 0)
			)
			(min_thickness 0.25)
			(keepout
				(tracks not_allowed)
				(vias allowed)
				(pads allowed)
				(copperpour not_allowed)
				(footprints allowed)
			)
			(placement
				(enabled no)
				(sheetname "")
			)
			(fill
				(thermal_gap 0.5)
				(thermal_bridge_width 0.5)
				(island_removal_mode 0)
			)
			(polygon
				(pts
					(xy 163.985194 -33.7185) (xy 164.975794 -33.7185) (xy 164.975794 -34.2265) (xy 163.985194 -34.2265)
				)
			)
		)
		(zone
			(layer "F.Cu")
			(hatch none 0.5)
			(connect_pads
				(clearance 0)
			)
			(min_thickness 0.25)
			(keepout
				(tracks allowed)
				(vias not_allowed)
				(pads allowed)
				(copperpour not_allowed)
				(footprints allowed)
			)
			(placement
				(enabled no)
				(sheetname "")
			)
			(fill
				(thermal_gap 0.5)
				(thermal_bridge_width 0.5)
				(island_removal_mode 0)
			)
			(polygon
				(pts
					(xy 163.985194 -33.7185) (xy 164.975794 -33.7185) (xy 164.975794 -34.2265) (xy 163.985194 -34.2265)
				)
			)
		)
	)
	(footprint ""
		(layer "F.Cu")
		(at 111.000032 -12.954 90)
		(property "Reference" "C3G2"
			(at 1.848866 0.752348 90)
			(unlocked yes)
			(layer "F.SilkS")
			(effects
				(font
					(size 1.27 0.9652)
					(thickness 0.1524)
				)
			)
		)
		(property "Value" ""
			(at 0 0 90)
			(layer "F.Fab")
			(effects
				(font
					(size 1.27 1.27)
				)
			)
		)
		(duplicate_pad_numbers_are_jumpers no)
		(fp_rect
			(start -0.500126 1.598422)
			(end 0.500126 -0.201422)
			(stroke
				(width 0)
				(type default)
			)
			(fill no)
			(layer "F.CrtYd")
		)
		(fp_line
			(start 0.500126 -0.201422)
			(end 0.500126 1.598422)
			(stroke
				(width 0.1)
				(type default)
			)
			(layer "F.Fab")
		)
		(fp_line
			(start -0.500126 -0.201422)
			(end 0.500126 -0.201422)
			(stroke
				(width 0.1)
				(type default)
			)
			(layer "F.Fab")
		)
		(fp_line
			(start 0.500126 1.598422)
			(end -0.500126 1.598422)
			(stroke
				(width 0.1)
				(type default)
			)
			(layer "F.Fab")
		)
		(fp_line
			(start -0.500126 1.598422)
			(end -0.500126 -0.201422)
			(stroke
				(width 0.1)
				(type default)
			)
			(layer "F.Fab")
		)
		(pad "1" smd rect
			(at 0 0)
			(size 0.889 0.9906)
			(layers "F.Cu" "F.Mask" "F.Paste")
			(net "PVDDQ_GHJ")
		)
		(pad "2" smd rect
			(at 0 1.397)
			(size 0.889 0.9906)
			(layers "F.Cu" "F.Mask" "F.Paste")
			(net "GND")
		)
		(zone
			(layer "F.Cu")
			(hatch none 0.5)
			(connect_pads
				(clearance 0)
			)
			(min_thickness 0.25)
			(keepout
				(tracks not_allowed)
				(vias allowed)
				(pads allowed)
				(copperpour not_allowed)
				(footprints allowed)
			)
			(placement
				(enabled no)
				(sheetname "")
			)
			(fill
				(thermal_gap 0.5)
				(thermal_bridge_width 0.5)
				(island_removal_mode 0)
			)
			(polygon
				(pts
					(xy 111.952532 -12.4587) (xy 111.952532 -13.4493) (xy 111.444532 -13.4493) (xy 111.444532 -12.4587)
				)
			)
		)
		(zone
			(layer "F.Cu")
			(hatch none 0.5)
			(connect_pads
				(clearance 0)
			)
			(min_thickness 0.25)
			(keepout
				(tracks allowed)
				(vias not_allowed)
				(pads allowed)
				(copperpour not_allowed)
				(footprints allowed)
			)
			(placement
				(enabled no)
				(sheetname "")
			)
			(fill
				(thermal_gap 0.5)
				(thermal_bridge_width 0.5)
				(island_removal_mode 0)
			)
			(polygon
				(pts
					(xy 111.952532 -12.4587) (xy 111.952532 -13.4493) (xy 111.444532 -13.4493) (xy 111.444532 -12.4587)
				)
			)
		)
	)
	(footprint ""
		(layer "F.Cu")
		(at 20.447 -70.866)
		(property "Reference" "R1D42"
			(at 0 0 0)
			(layer "F.SilkS")
			(hide yes)
			(effects
				(font
					(size 1.27 1.27)
				)
			)
		)
		(property "Value" ""
			(at 0 0 0)
			(layer "F.Fab")
			(effects
				(font
					(size 1.27 1.27)
				)
			)
		)
		(duplicate_pad_numbers_are_jumpers no)
		(fp_rect
			(start 0.2794 0.9906)
			(end -0.2794 -0.1016)
			(stroke
				(width 0)
				(type default)
			)
			(fill no)
			(layer "F.CrtYd")
		)
		(fp_line
			(start -0.2794 -0.1016)
			(end -0.2794 0.9906)
			(stroke
				(width 0.1)
				(type default)
			)
			(layer "F.Fab")
		)
		(fp_line
			(start -0.2794 0.9906)
			(end 0.2794 0.9906)
			(stroke
				(width 0.1)
				(type default)
			)
			(layer "F.Fab")
		)
		(fp_line
			(start 0.2794 -0.1016)
			(end -0.2794 -0.1016)
			(stroke
				(width 0.1)
				(type default)
			)
			(layer "F.Fab")
		)
		(fp_line
			(start 0.2794 0.9906)
			(end 0.2794 -0.1016)
			(stroke
				(width 0.1)
				(type default)
			)
			(layer "F.Fab")
		)
		(pad "1" smd rect
			(at 0 0)
			(size 0.508 0.508)
			(layers "F.Cu" "F.Mask" "F.Paste")
			(net "A_HSC_UV")
		)
		(pad "2" smd rect
			(at 0 0.889)
			(size 0.508 0.508)
			(layers "F.Cu" "F.Mask" "F.Paste")
			(net "AGND_HSC")
		)
		(zone
			(layer "F.Cu")
			(hatch none 0.5)
			(connect_pads
				(clearance 0)
			)
			(min_thickness 0.25)
			(keepout
				(tracks allowed)
				(vias not_allowed)
				(pads allowed)
				(copperpour not_allowed)
				(footprints allowed)
			)
			(placement
				(enabled no)
				(sheetname "")
			)
			(fill
				(thermal_gap 0.5)
				(thermal_bridge_width 0.5)
				(island_removal_mode 0)
			)
			(polygon
				(pts
					(xy 20.701 -70.231) (xy 20.701 -70.612) (xy 20.193 -70.612) (xy 20.193 -70.231)
				)
			)
		)
		(zone
			(layer "F.Cu")
			(hatch none 0.5)
			(connect_pads
				(clearance 0)
			)
			(min_thickness 0.25)
			(keepout
				(tracks not_allowed)
				(vias allowed)
				(pads allowed)
				(copperpour not_allowed)
				(footprints allowed)
			)
			(placement
				(enabled no)
				(sheetname "")
			)
			(fill
				(thermal_gap 0.5)
				(thermal_bridge_width 0.5)
				(island_removal_mode 0)
			)
			(polygon
				(pts
					(xy 20.701 -70.231) (xy 20.701 -70.612) (xy 20.193 -70.612) (xy 20.193 -70.231)
				)
			)
		)
	)
)
